(kicad_pcb
	(version 20241229)
	(generator "pcbnew")
	(generator_version "9.0")
	(general
		(thickness 1.552)
		(legacy_teardrops no)
	)
	(paper "A4")
	(title_block
		(date "2023-07-25")
		(rev "1.1.4")
		(comment 9 "footprints 213-218 of 379")
	)
	(layers
		(0 "F.Cu" signal)
		(4 "In1.Cu" signal)
		(6 "In2.Cu" signal)
		(8 "In3.Cu" signal)
		(10 "In4.Cu" signal)
		(12 "In5.Cu" signal)
		(14 "In6.Cu" signal)
		(2 "B.Cu" signal)
		(9 "F.Adhes" user "F.Adhesive")
		(11 "B.Adhes" user "B.Adhesive")
		(13 "F.Paste" user)
		(15 "B.Paste" user)
		(5 "F.SilkS" user "F.Silkscreen")
		(7 "B.SilkS" user "B.Silkscreen")
		(1 "F.Mask" user)
		(3 "B.Mask" user)
		(17 "Dwgs.User" user "User.Drawings")
		(19 "Cmts.User" user "User.Comments")
		(21 "Eco1.User" user "User.Eco1")
		(23 "Eco2.User" user "User.Eco2")
		(25 "Edge.Cuts" user)
		(27 "Margin" user)
		(31 "F.CrtYd" user "F.Courtyard")
		(29 "B.CrtYd" user "B.Courtyard")
		(35 "F.Fab" user)
		(33 "B.Fab" user)
	)
	(footprint "antmicro-footprints:R_0402_1005Metric"
		(layer "F.Cu")
		(at 83.7 109.65 -90)
		(descr "Resistor SMD 0402")
		(tags "resistor SMD 0402")
		(property "Reference" "R62"
			(at -9.21 -3.43 90)
			(layer "F.SilkS")
			(effects
				(font
					(size 0.65 0.65)
					(thickness 0.15)
				)
				(justify right bottom)
			)
		)
		(property "Value" "R_75R_0402"
			(at 0 1.4 90)
			(layer "F.Fab")
			(hide yes)
			(effects
				(font
					(size 0.7 0.7)
					(thickness 0.15)
				)
				(justify right bottom)
			)
		)
		(property "Datasheet" "https://www.bourns.com/docs/product-datasheets/cr.pdf"
			(at 0 0 270)
			(layer "F.Fab")
			(hide yes)
			(effects
				(font
					(size 1.27 1.27)
					(thickness 0.15)
				)
			)
		)
		(property "Description" "SMD Chip Resistor, 75 ohm, ± 1%, 62.5 mW, 0402 [1005 Metric], Thick Film, General Purpose"
			(at 0 0 270)
			(layer "F.Fab")
			(hide yes)
			(effects
				(font
					(size 1.27 1.27)
					(thickness 0.15)
				)
			)
		)
		(property "Author" "Antmicro"
			(at -25.95 193.35 0)
			(layer "F.Fab")
			(hide yes)
			(effects
				(font
					(size 1 1)
					(thickness 0.15)
				)
			)
		)
		(property "License" "Apache-2.0"
			(at -25.95 193.35 0)
			(layer "F.Fab")
			(hide yes)
			(effects
				(font
					(size 1 1)
					(thickness 0.15)
				)
			)
		)
		(property "MPN" "CR0402-FX-75R0GLF"
			(at -25.95 193.35 0)
			(layer "F.Fab")
			(hide yes)
			(effects
				(font
					(size 1 1)
					(thickness 0.15)
				)
			)
		)
		(property "Manufacturer" "Bourns"
			(at -25.95 193.35 0)
			(layer "F.Fab")
			(hide yes)
			(effects
				(font
					(size 1 1)
					(thickness 0.15)
				)
			)
		)
		(property "Tolerance" "1%"
			(at -25.95 193.35 0)
			(layer "F.Fab")
			(hide yes)
			(effects
				(font
					(size 1 1)
					(thickness 0.15)
				)
			)
		)
		(property "Val" "75R"
			(at -25.95 193.35 0)
			(layer "F.Fab")
			(hide yes)
			(effects
				(font
					(size 1 1)
					(thickness 0.15)
				)
			)
		)
		(sheetname "/SDI/")
		(sheetfile "sdi.kicad_sch")
		(attr smd)
		(fp_rect
			(start -0.925 -0.47)
			(end 0.925 0.47)
			(stroke
				(width 0.05)
				(type default)
			)
			(fill no)
			(layer "F.CrtYd")
		)
		(fp_rect
			(start -0.5 -0.25)
			(end 0.5 0.25)
			(stroke
				(width 0.15)
				(type solid)
			)
			(fill no)
			(layer "F.Fab")
		)
		(fp_text user "Author: Antmicro"
			(at -0.95 4.169 270)
			(layer "F.Fab")
			(effects
				(font
					(size 0.7 0.7)
					(thickness 0.15)
				)
				(justify left bottom)
			)
		)
		(fp_text user "${REFERENCE}"
			(at -0.95 3.168 270)
			(layer "F.Fab")
			(effects
				(font
					(size 0.7 0.7)
					(thickness 0.15)
				)
				(justify left bottom)
			)
		)
		(fp_text user "License: Apache-2.0"
			(at -0.95 5.169 270)
			(layer "F.Fab")
			(effects
				(font
					(size 0.7 0.7)
					(thickness 0.15)
				)
				(justify left bottom)
			)
		)
		(pad "1" smd roundrect
			(at -0.48 0 270)
			(size 0.59 0.64)
			(layers "F.Cu" "F.Mask" "F.Paste")
			(roundrect_rratio 0.25)
			(net 250 "Net-(C77-Pad2)")
			(pintype "passive")
		)
		(pad "2" smd roundrect
			(at 0.48 0 270)
			(size 0.59 0.64)
			(layers "F.Cu" "F.Mask" "F.Paste")
			(roundrect_rratio 0.25)
			(net 1 "GND")
			(pintype "passive")
		)
	)
	(footprint "antmicro-footprints:C_0603_1608Metric"
		(layer "F.Cu")
		(at 151.48 64.75 90)
		(descr "Capacitor SMD 0603")
		(tags "capacitor 0603")
		(property "Reference" "C124"
			(at -1.24 -1.07 90)
			(layer "F.SilkS")
			(effects
				(font
					(size 0.65 0.65)
					(thickness 0.15)
				)
				(justify left bottom)
			)
		)
		(property "Value" "C_1u_0603"
			(at 0 1.6 90)
			(layer "F.Fab")
			(hide yes)
			(effects
				(font
					(size 0.7 0.7)
					(thickness 0.15)
				)
				(justify left bottom)
			)
		)
		(property "Datasheet" "https://spicat.kyocera-avx.com/product/mlcc/chartview/0603YD105KAT2A/"
			(at 0 0 90)
			(layer "F.Fab")
			(hide yes)
			(effects
				(font
					(size 1.27 1.27)
					(thickness 0.15)
				)
			)
		)
		(property "Description" "SMD Multilayer Ceramic Capacitor, 1 µF, 16 V, 0603 [1608 Metric], ± 10%, X5R, AVX 0603 MLCC"
			(at 0 0 90)
			(layer "F.Fab")
			(hide yes)
			(effects
				(font
					(size 1.27 1.27)
					(thickness 0.15)
				)
			)
		)
		(property "Author" "Antmicro"
			(at 216.2 -86.7 0)
			(layer "F.Fab")
			(hide yes)
			(effects
				(font
					(size 1 1)
					(thickness 0.15)
				)
			)
		)
		(property "Dielectric" ""
			(at 216.2 -86.7 0)
			(layer "F.Fab")
			(hide yes)
			(effects
				(font
					(size 1 1)
					(thickness 0.15)
				)
			)
		)
		(property "License" "Apache-2.0"
			(at 216.2 -86.7 0)
			(layer "F.Fab")
			(hide yes)
			(effects
				(font
					(size 1 1)
					(thickness 0.15)
				)
			)
		)
		(property "MPN" "0603YD105KAT2A"
			(at 216.2 -86.7 0)
			(layer "F.Fab")
			(hide yes)
			(effects
				(font
					(size 1 1)
					(thickness 0.15)
				)
			)
		)
		(property "Manufacturer" "KYOCERA AVX"
			(at 216.2 -86.7 0)
			(layer "F.Fab")
			(hide yes)
			(effects
				(font
					(size 1 1)
					(thickness 0.15)
				)
			)
		)
		(property "Val" "1u"
			(at 216.2 -86.7 0)
			(layer "F.Fab")
			(hide yes)
			(effects
				(font
					(size 1 1)
					(thickness 0.15)
				)
			)
		)
		(property "Voltage" ""
			(at 216.2 -86.7 0)
			(layer "F.Fab")
			(hide yes)
			(effects
				(font
					(size 1 1)
					(thickness 0.15)
				)
			)
		)
		(sheetname "/Peripherals/")
		(sheetfile "peripherals.kicad_sch")
		(attr smd)
		(fp_line
			(start -0.15 -0.4)
			(end 0.15 -0.4)
			(stroke
				(width 0.15)
				(type solid)
			)
			(layer "F.SilkS")
		)
		(fp_line
			(start -0.15 0.4)
			(end 0.15 0.4)
			(stroke
				(width 0.15)
				(type solid)
			)
			(layer "F.SilkS")
		)
		(fp_rect
			(start -1.25 -0.65)
			(end 1.25 0.65)
			(stroke
				(width 0.05)
				(type solid)
			)
			(fill no)
			(layer "F.CrtYd")
		)
		(fp_rect
			(start -0.8 -0.4)
			(end 0.8 0.4)
			(stroke
				(width 0.15)
				(type solid)
			)
			(fill no)
			(layer "F.Fab")
		)
		(fp_text user "Author: Antmicro"
			(at -1.682 4.894 90)
			(layer "F.Fab")
			(effects
				(font
					(size 0.7 0.7)
					(thickness 0.15)
				)
				(justify left bottom)
			)
		)
		(fp_text user "${REFERENCE}"
			(at -1.682 3.895 90)
			(layer "F.Fab")
			(effects
				(font
					(size 0.7 0.7)
					(thickness 0.15)
				)
				(justify left bottom)
			)
		)
		(fp_text user "License: Apache-2.0"
			(at -1.682 5.895 90)
			(layer "F.Fab")
			(effects
				(font
					(size 0.7 0.7)
					(thickness 0.15)
				)
				(justify left bottom)
			)
		)
		(pad "1" smd roundrect
			(at -0.7 0 90)
			(size 0.8 1)
			(layers "F.Cu" "F.Mask" "F.Paste")
			(roundrect_rratio 0.2)
			(net 1 "GND")
			(pintype "passive")
		)
		(pad "2" smd roundrect
			(at 0.7 0 90)
			(size 0.8 1)
			(layers "F.Cu" "F.Mask" "F.Paste")
			(roundrect_rratio 0.2)
			(net 325 "USB_POWER_IN")
			(pintype "passive")
		)
	)
	(footprint "antmicro-footprints:R_0402_1005Metric"
		(layer "F.Cu")
		(at 144.28 77.14 180)
		(descr "Resistor SMD 0402")
		(tags "resistor SMD 0402")
		(property "Reference" "R23"
			(at 3.05 -0.39 180)
			(layer "F.SilkS")
			(effects
				(font
					(size 0.65 0.65)
					(thickness 0.15)
				)
				(justify left bottom)
			)
		)
		(property "Value" "R_10k_0402"
			(at 0 1.4 180)
			(layer "F.Fab")
			(hide yes)
			(effects
				(font
					(size 0.7 0.7)
					(thickness 0.15)
				)
				(justify left bottom)
			)
		)
		(property "Datasheet" "https://www.bourns.com/docs/product-datasheets/cr.pdf"
			(at 0 0 180)
			(layer "F.Fab")
			(hide yes)
			(effects
				(font
					(size 1.27 1.27)
					(thickness 0.15)
				)
			)
		)
		(property "Description" "SMD Chip Resistor, 10 kohm, ± 1%, 62.5 mW, 0402 [1005 Metric], Thick Film, General Purpose"
			(at 0 0 180)
			(layer "F.Fab")
			(hide yes)
			(effects
				(font
					(size 1.27 1.27)
					(thickness 0.15)
				)
			)
		)
		(property "Author" "Antmicro"
			(at 288.56 154.1 0)
			(layer "F.Fab")
			(hide yes)
			(effects
				(font
					(size 1 1)
					(thickness 0.15)
				)
			)
		)
		(property "License" "Apache-2.0"
			(at 288.56 154.1 0)
			(layer "F.Fab")
			(hide yes)
			(effects
				(font
					(size 1 1)
					(thickness 0.15)
				)
			)
		)
		(property "MPN" "CR0402-FX-1002GLF"
			(at 288.56 154.1 0)
			(layer "F.Fab")
			(hide yes)
			(effects
				(font
					(size 1 1)
					(thickness 0.15)
				)
			)
		)
		(property "Manufacturer" "Bourns"
			(at 288.56 154.1 0)
			(layer "F.Fab")
			(hide yes)
			(effects
				(font
					(size 1 1)
					(thickness 0.15)
				)
			)
		)
		(property "Tolerance" "1%"
			(at 288.56 154.1 0)
			(layer "F.Fab")
			(hide yes)
			(effects
				(font
					(size 1 1)
					(thickness 0.15)
				)
			)
		)
		(property "Val" "10k"
			(at 288.56 154.1 0)
			(layer "F.Fab")
			(hide yes)
			(effects
				(font
					(size 1 1)
					(thickness 0.15)
				)
			)
		)
		(sheetname "/Power Supply/")
		(sheetfile "supply.kicad_sch")
		(attr smd)
		(fp_rect
			(start -0.925 -0.47)
			(end 0.925 0.47)
			(stroke
				(width 0.05)
				(type default)
			)
			(fill no)
			(layer "F.CrtYd")
		)
		(fp_rect
			(start -0.5 -0.25)
			(end 0.5 0.25)
			(stroke
				(width 0.15)
				(type solid)
			)
			(fill no)
			(layer "F.Fab")
		)
		(fp_text user "License: Apache-2.0"
			(at -0.95 5.169 180)
			(layer "F.Fab")
			(effects
				(font
					(size 0.7 0.7)
					(thickness 0.15)
				)
				(justify left bottom)
			)
		)
		(fp_text user "Author: Antmicro"
			(at -0.95 4.169 180)
			(layer "F.Fab")
			(effects
				(font
					(size 0.7 0.7)
					(thickness 0.15)
				)
				(justify left bottom)
			)
		)
		(fp_text user "${REFERENCE}"
			(at -0.95 3.168 180)
			(layer "F.Fab")
			(effects
				(font
					(size 0.7 0.7)
					(thickness 0.15)
				)
				(justify left bottom)
			)
		)
		(pad "1" smd roundrect
			(at -0.48 0 180)
			(size 0.59 0.64)
			(layers "F.Cu" "F.Mask" "F.Paste")
			(roundrect_rratio 0.25)
			(net 1 "GND")
			(pintype "passive")
		)
		(pad "2" smd roundrect
			(at 0.48 0 180)
			(size 0.59 0.64)
			(layers "F.Cu" "F.Mask" "F.Paste")
			(roundrect_rratio 0.25)
			(net 267 "Net-(U5-FB)")
			(pintype "passive")
		)
	)
	(footprint "antmicro-footprints:R_0402_1005Metric"
		(layer "F.Cu")
		(at 122.03 114.15)
		(descr "Resistor SMD 0402")
		(tags "resistor SMD 0402")
		(property "Reference" "R84"
			(at -3.9 0.29 0)
			(layer "F.SilkS")
			(effects
				(font
					(size 0.65 0.65)
					(thickness 0.15)
				)
				(justify left bottom)
			)
		)
		(property "Value" "R_100R_0402"
			(at 0 1.4 0)
			(layer "F.Fab")
			(hide yes)
			(effects
				(font
					(size 0.7 0.7)
					(thickness 0.15)
				)
				(justify left bottom)
			)
		)
		(property "Datasheet" "https://www.bourns.com/docs/product-datasheets/cr.pdf"
			(at 0 0 0)
			(layer "F.Fab")
			(hide yes)
			(effects
				(font
					(size 1.27 1.27)
					(thickness 0.15)
				)
			)
		)
		(property "Description" "SMD Chip Resistor, 100 ohm, ± 1%, 62.5 mW, 0402 [1005 Metric], Thick Film, General Purpose"
			(at 0 0 0)
			(layer "F.Fab")
			(hide yes)
			(effects
				(font
					(size 1.27 1.27)
					(thickness 0.15)
				)
			)
		)
		(property "Author" "Antmicro"
			(at 0 0 0)
			(layer "F.Fab")
			(hide yes)
			(effects
				(font
					(size 1 1)
					(thickness 0.15)
				)
			)
		)
		(property "License" "Apache-2.0"
			(at 0 0 0)
			(layer "F.Fab")
			(hide yes)
			(effects
				(font
					(size 1 1)
					(thickness 0.15)
				)
			)
		)
		(property "MPN" "CR0402-FX-1000GLF"
			(at 0 0 0)
			(layer "F.Fab")
			(hide yes)
			(effects
				(font
					(size 1 1)
					(thickness 0.15)
				)
			)
		)
		(property "Manufacturer" "Bourns"
			(at 0 0 0)
			(layer "F.Fab")
			(hide yes)
			(effects
				(font
					(size 1 1)
					(thickness 0.15)
				)
			)
		)
		(property "Tolerance" "1%"
			(at 0 0 0)
			(layer "F.Fab")
			(hide yes)
			(effects
				(font
					(size 1 1)
					(thickness 0.15)
				)
			)
		)
		(property "Val" "100R"
			(at 0 0 0)
			(layer "F.Fab")
			(hide yes)
			(effects
				(font
					(size 1 1)
					(thickness 0.15)
				)
			)
		)
		(sheetname "/FPGA/")
		(sheetfile "fpga.kicad_sch")
		(attr smd)
		(fp_rect
			(start -0.925 -0.47)
			(end 0.925 0.47)
			(stroke
				(width 0.05)
				(type default)
			)
			(fill no)
			(layer "F.CrtYd")
		)
		(fp_rect
			(start -0.5 -0.25)
			(end 0.5 0.25)
			(stroke
				(width 0.15)
				(type solid)
			)
			(fill no)
			(layer "F.Fab")
		)
		(fp_text user "License: Apache-2.0"
			(at -0.95 5.169 0)
			(layer "F.Fab")
			(effects
				(font
					(size 0.7 0.7)
					(thickness 0.15)
				)
				(justify left bottom)
			)
		)
		(fp_text user "${REFERENCE}"
			(at -0.95 3.168 0)
			(layer "F.Fab")
			(effects
				(font
					(size 0.7 0.7)
					(thickness 0.15)
				)
				(justify left bottom)
			)
		)
		(fp_text user "Author: Antmicro"
			(at -0.95 4.169 0)
			(layer "F.Fab")
			(effects
				(font
					(size 0.7 0.7)
					(thickness 0.15)
				)
				(justify left bottom)
			)
		)
		(pad "1" smd roundrect
			(at -0.48 0)
			(size 0.59 0.64)
			(layers "F.Cu" "F.Mask" "F.Paste")
			(roundrect_rratio 0.25)
			(net 40 "/FPGA/DONE")
			(pintype "passive")
		)
		(pad "2" smd roundrect
			(at 0.48 0)
			(size 0.59 0.64)
			(layers "F.Cu" "F.Mask" "F.Paste")
			(roundrect_rratio 0.25)
			(net 261 "Net-(Q6-G)")
			(pintype "passive")
		)
	)
	(footprint "antmicro-footprints:TP_SMD_0.75mm"
		(layer "F.Cu")
		(at 145 91.2608)
		(property "Reference" "TP47"
			(at -3.07 0.3792 0)
			(layer "F.SilkS")
			(effects
				(font
					(size 0.65 0.65)
					(thickness 0.15)
				)
				(justify left bottom)
			)
		)
		(property "Value" "TP_0.75mm_SMD"
			(at 0 1.2 0)
			(layer "F.Fab")
			(hide yes)
			(effects
				(font
					(size 0.7 0.7)
					(thickness 0.15)
				)
				(justify left bottom)
			)
		)
		(property "Description" "SMT test point"
			(at 0 0 0)
			(layer "F.Fab")
			(hide yes)
			(effects
				(font
					(size 1.27 1.27)
					(thickness 0.15)
				)
			)
		)
		(property "Author" "Antmicro"
			(at 0 0 0)
			(layer "F.Fab")
			(hide yes)
			(effects
				(font
					(size 1 1)
					(thickness 0.15)
				)
			)
		)
		(property "License" "Apache-2.0"
			(at 0 0 0)
			(layer "F.Fab")
			(hide yes)
			(effects
				(font
					(size 1 1)
					(thickness 0.15)
				)
			)
		)
		(property "MPN" ""
			(at 0 0 0)
			(layer "F.Fab")
			(hide yes)
			(effects
				(font
					(size 1 1)
					(thickness 0.15)
				)
			)
		)
		(property "Manufacturer" ""
			(at 0 0 0)
			(layer "F.Fab")
			(hide yes)
			(effects
				(font
					(size 1 1)
					(thickness 0.15)
				)
			)
		)
		(sheetname "/Peripherals/")
		(sheetfile "peripherals.kicad_sch")
		(attr exclude_from_pos_files)
		(fp_circle
			(center 0 0)
			(end 0.475 0)
			(stroke
				(width 0.05)
				(type default)
			)
			(fill no)
			(layer "F.CrtYd")
		)
		(fp_text user "Author: Antmicro"
			(at -0.4 3.901 0)
			(layer "F.Fab")
			(effects
				(font
					(size 0.7 0.7)
					(thickness 0.15)
				)
				(justify left bottom)
			)
		)
		(fp_text user "${REFERENCE}"
			(at -0.4 2.7 0)
			(layer "F.Fab")
			(effects
				(font
					(size 0.7 0.7)
					(thickness 0.15)
				)
				(justify left bottom)
			)
		)
		(fp_text user "License: Apache-2.0"
			(at -0.4 5.101 0)
			(layer "F.Fab")
			(effects
				(font
					(size 0.7 0.7)
					(thickness 0.15)
				)
				(justify left bottom)
			)
		)
		(pad "1" smd circle
			(at 0 0)
			(size 0.75 0.75)
			(layers "F.Cu" "F.Mask")
			(net 380 "Net-(U20-CBUS3)")
			(pinfunction "1")
			(pintype "passive")
		)
	)
	(footprint "antmicro-footprints:R_0402_1005Metric"
		(layer "F.Cu")
		(at 98.94 115.185 90)
		(descr "Resistor SMD 0402")
		(tags "resistor SMD 0402")
		(property "Reference" "R88"
			(at 0.895 0.39 90)
			(layer "F.SilkS")
			(effects
				(font
					(size 0.65 0.65)
					(thickness 0.15)
				)
				(justify left bottom)
			)
		)
		(property "Value" "R_0R_0402"
			(at 0 1.4 90)
			(layer "F.Fab")
			(hide yes)
			(effects
				(font
					(size 0.7 0.7)
					(thickness 0.15)
				)
				(justify left bottom)
			)
		)
		(property "Datasheet" "https://industrial.panasonic.com/cdbs/www-data/pdf/RDA0000/AOA0000C301.pdf"
			(at 0 0 90)
			(layer "F.Fab")
			(hide yes)
			(effects
				(font
					(size 1.27 1.27)
					(thickness 0.15)
				)
			)
		)
		(property "Description" "SMD Chip Resistor, Jumper, 0 ohm, 100 mW, 0402 [1005 Metric], Thick Film, General Purpose"
			(at 0 0 90)
			(layer "F.Fab")
			(hide yes)
			(effects
				(font
					(size 1.27 1.27)
					(thickness 0.15)
				)
			)
		)
		(property "Author" "Antmicro"
			(at 214.125 16.245 0)
			(layer "F.Fab")
			(hide yes)
			(effects
				(font
					(size 1 1)
					(thickness 0.15)
				)
			)
		)
		(property "Current" "1A"
			(at 214.125 16.245 0)
			(layer "F.Fab")
			(hide yes)
			(effects
				(font
					(size 1 1)
					(thickness 0.15)
				)
			)
		)
		(property "License" "Apache-2.0"
			(at 214.125 16.245 0)
			(layer "F.Fab")
			(hide yes)
			(effects
				(font
					(size 1 1)
					(thickness 0.15)
				)
			)
		)
		(property "MPN" "ERJ2GE0R00X"
			(at 214.125 16.245 0)
			(layer "F.Fab")
			(hide yes)
			(effects
				(font
					(size 1 1)
					(thickness 0.15)
				)
			)
		)
		(property "Manufacturer" "Panasonic"
			(at 214.125 16.245 0)
			(layer "F.Fab")
			(hide yes)
			(effects
				(font
					(size 1 1)
					(thickness 0.15)
				)
			)
		)
		(property "Tolerance" "~"
			(at 214.125 16.245 0)
			(layer "F.Fab")
			(hide yes)
			(effects
				(font
					(size 1 1)
					(thickness 0.15)
				)
			)
		)
		(property "Val" "0R"
			(at 214.125 16.245 0)
			(layer "F.Fab")
			(hide yes)
			(effects
				(font
					(size 1 1)
					(thickness 0.15)
				)
			)
		)
		(sheetname "/FPGA/")
		(sheetfile "fpga.kicad_sch")
		(attr smd)
		(fp_rect
			(start -0.925 -0.47)
			(end 0.925 0.47)
			(stroke
				(width 0.05)
				(type default)
			)
			(fill no)
			(layer "F.CrtYd")
		)
		(fp_rect
			(start -0.5 -0.25)
			(end 0.5 0.25)
			(stroke
				(width 0.15)
				(type solid)
			)
			(fill no)
			(layer "F.Fab")
		)
		(fp_text user "${REFERENCE}"
			(at -0.95 3.168 90)
			(layer "F.Fab")
			(effects
				(font
					(size 0.7 0.7)
					(thickness 0.15)
				)
				(justify left bottom)
			)
		)
		(fp_text user "Author: Antmicro"
			(at -0.95 4.169 90)
			(layer "F.Fab")
			(effects
				(font
					(size 0.7 0.7)
					(thickness 0.15)
				)
				(justify left bottom)
			)
		)
		(fp_text user "License: Apache-2.0"
			(at -0.95 5.169 90)
			(layer "F.Fab")
			(effects
				(font
					(size 0.7 0.7)
					(thickness 0.15)
				)
				(justify left bottom)
			)
		)
		(pad "1" smd roundrect
			(at -0.48 0 90)
			(size 0.59 0.64)
			(layers "F.Cu" "F.Mask" "F.Paste")
			(roundrect_rratio 0.25)
			(net 134 "Net-(J7-Pad2)")
			(pintype "passive")
		)
		(pad "2" smd roundrect
			(at 0.48 0 90)
			(size 0.59 0.64)
			(layers "F.Cu" "F.Mask" "F.Paste")
			(roundrect_rratio 0.25)
			(net 169 "TMS")
			(pintype "passive")
		)
	)
)
